FILE_TYPE = CONNECTIVITY;
{Allegro Design Entry HDL 17.2-2016 S081 (4005846) 1/11/2022}
"PAGE_NUMBER" = 191;
0"NC";
1"P1V05_PCH_AUX\g";
2"P3V3_AUX\g";
3"H_THERMTRIP_LVC1_N";
4"FM_PCH_BMC_THERMTRIP_N";
5"FM_THERMTRIP_DLY_LVC1_N";
6"FM_PLT_BMC_THERMTRIP_R_N";
7"FM_PCH_CPU_PWR_DEBUG_N";
8"FM_CPU_FBRK_DEBUG_N";
%"Q_RES"
"1","(-1675,975)","0","pure_quanta","I14";
;
PART_NUMBER"CS00002JB13"
MATERIAL"CHIP"
PACK_TYPE"0402LF"
WATTAGE"1/16W"
TOLERANCE"5%"
VALUE"0"
$LOCATION"R1247"
CDS_LIB"pure_quanta"
$LOCATION"R1247"
CDS_LOCATION"R1247"
$SEC"1"
CDS_SEC"1";
"B"
$PN"2"8;
"A"
$PN"1"7;
%"Q_RES"
"1","(-1675,4150)","0","pure_quanta","I2";
;
PART_NUMBER"CS00002JB13"
WATTAGE"1/16W"
MATERIAL"CHIP"
TOLERANCE"5%"
PACK_TYPE"0402LF"
VALUE"0"
$LOCATION"R1249"
CDS_LIB"pure_quanta"
$LOCATION"R1249"
CDS_LOCATION"R1249"
$SEC"1"
CDS_SEC"1";
"B"
$PN"2"3;
"A"
$PN"1"5;
%"Q_RES"
"1","(-1750,3125)","0","pure_quanta","I29";
;
PART_NUMBER"CS03322FB03"
PACK_TYPE"0402LF"
MATERIAL"CHIP"
VALUE"33.2"
WATTAGE"1/16W"
TOLERANCE"1%"
$LOCATION"R1263"
CDS_LIB"pure_quanta"
CDS_LOCATION"R1263"
$SEC"1"
CDS_SEC"1";
"B"
$PN"2"4;
"A"
$PN"1"6;
%"UNIVERSAL_POWER"
"1","(-2775,3700)","0","logical_power","I34";
;
HDL_POWER"P3V3_AUX"
CDS_LIB"logical_power";
"A"2;
%"Q_RES"
"2","(-2775,3450)","0","pure_quanta","I35";
;
PART_NUMBER"CS31002FB08"
MATERIAL"CHIP"
VALUE"10K"
PACK_TYPE"0402LF"
WATTAGE"1/16W"
TOLERANCE"1%"
$LOCATION"R1820"
CDS_LIB"pure_quanta"
CDS_LOCATION"R1820"
$SEC"1"
CDS_SEC"1";
"A"
$PN"1"2;
"B"
$PN"2"6;
%"UNIVERSAL_POWER"
"1","(175,4650)","0","logical_power","I37";
;
HDL_POWER"P1V05_PCH_AUX"
CDS_LIB"logical_power";
"A"1;
%"Q_RES"
"2","(175,4400)","0","pure_quanta","I38";
;
PART_NUMBER"CS07502FB04"
TOLERANCE"1%"
VALUE"75"
PACK_TYPE"0402LF"
MATERIAL"CHIP"
WATTAGE"1/16W"
LOCATION"R1266"
CDS_LIB"pure_quanta"
$SEC"1"
CDS_SEC"1";
"A"
$PN"1"1;
"B"
$PN"2"3;
END.
